FILE_TYPE = CONNECTIVITY;
{Allegro Design Entry HDL 17.2-2016 S081 (4005846) 1/11/2022}
"PAGE_NUMBER" = 57;
0"NC";
1"PVDD18_S5_P1\g";
2"P1V5_BAT\g";
3"PVDDIO_P1\g";
4"PVDDCR_CPU0_P1\g";
5"PVDDCR_CPU0_P1\g";
6"PVDDCR_CPU1_P1\g";
7"PVDDCR_CPU1_P1\g";
8"PVDDCR_SOC_P1\g";
9"PVDD_33_S5\g";
10"PVDD18_S5_P1\g";
11"PVDD11_S3_P1\g";
12"PVDDCR_SOC_P1\g";
13"CPU1_VDDBT_RTC_G";
%"VCC_CORE"
"1","(-7425,6600)","0","pure_quanta_power","I27";
;
HDL_POWER"PVDDCR_CPU0_P1"
CDS_LIB"pure_quanta_power";
"A"5;
%"VCC_CORE"
"1","(-8875,6600)","0","pure_quanta_power","I28";
;
HDL_POWER"PVDDCR_CPU0_P1"
CDS_LIB"pure_quanta_power";
"A"4;
%"GENOA_SP5"
"24","(-8150,3350)","0","pure_quanta","I29";
;
LOCATION"U26"
$SEC"24"
CDS_SEC"24"
MATERIAL"IO"
PART_TYPE"SMLF"
PART_NUMBER"DGA^6000030"
VALUE"SOCKET6096_13568-001"
CDS_LIB"pure_quanta"
CDS_LMAN_SYM_OUTLINE"-500,3150,500,-3150"
NEEDS_NO_SIZE"TRUE";
"VDDCR_CPU0_AU33"
$PN"AU33"5;
"VDDCR_CPU0_AU25"
$PN"AU25"5;
"VDDCR_CPU0_AU48"
$PN"AU48"5;
"VDDCR_CPU0_AU44"
$PN"AU44"5;
"VDDCR_CPU0_AU29"
$PN"AU29"5;
"VDDCR_CPU0_AT49"
$PN"AT49"5;
"VDDCR_CPU0_AU46"
$PN"AU46"5;
"VDDCR_CPU0_AU42"
$PN"AU42"5;
"VDDCR_CPU0_Y35"
$PN"Y35"5;
"VDDCR_CPU0_Y36"
$PN"Y36"5;
"VDDCR_CPU0_Y40"
$PN"Y40"5;
"VDDCR_CPU0_Y41"
$PN"Y41"5;
"VDDCR_CPU0_AB23"
$PN"AB23"5;
"VDDCR_CPU0_AB24"
$PN"AB24"5;
"VDDCR_CPU0_AB26"
$PN"AB26"5;
"VDDCR_CPU0_AB27"
$PN"AB27"5;
"VDDCR_CPU0_AB29"
$PN"AB29"5;
"VDDCR_CPU0_AB30"
$PN"AB30"5;
"VDDCR_CPU0_AB32"
$PN"AB32"5;
"VDDCR_CPU0_AB33"
$PN"AB33"5;
"VDDCR_CPU0_AB43"
$PN"AB43"5;
"VDDCR_CPU0_AB44"
$PN"AB44"5;
"VDDCR_CPU0_AB46"
$PN"AB46"5;
"VDDCR_CPU0_AB47"
$PN"AB47"5;
"VDDCR_CPU0_AB49"
$PN"AB49"5;
"VDDCR_CPU0_AB50"
$PN"AB50"5;
"VDDCR_CPU0_AB52"
$PN"AB52"5;
"VDDCR_CPU0_AB53"
$PN"AB53"5;
"VDDCR_CPU0_AC35"
$PN"AC35"5;
"VDDCR_CPU0_AC36"
$PN"AC36"5;
"VDDCR_CPU0_AC40"
$PN"AC40"5;
"VDDCR_CPU0_AC41"
$PN"AC41"5;
"VDDCR_CPU0_AF23"
$PN"AF23"5;
"VDDCR_CPU0_AF24"
$PN"AF24"5;
"VDDCR_CPU0_AF26"
$PN"AF26"5;
"VDDCR_CPU0_AF27"
$PN"AF27"5;
"VDDCR_CPU0_AF29"
$PN"AF29"5;
"VDDCR_CPU0_AF30"
$PN"AF30"5;
"VDDCR_CPU0_AF32"
$PN"AF32"5;
"VDDCR_CPU0_AF33"
$PN"AF33"5;
"VDDCR_CPU0_AF43"
$PN"AF43"5;
"VDDCR_CPU0_AF44"
$PN"AF44"5;
"VDDCR_CPU0_AF46"
$PN"AF46"5;
"VDDCR_CPU0_AF47"
$PN"AF47"5;
"VDDCR_CPU0_AF49"
$PN"AF49"5;
"VDDCR_CPU0_AF50"
$PN"AF50"5;
"VDDCR_CPU0_AF52"
$PN"AF52"5;
"VDDCR_CPU0_AF53"
$PN"AF53"5;
"VDDCR_CPU0_AG35"
$PN"AG35"5;
"VDDCR_CPU0_AG36"
$PN"AG36"5;
"VDDCR_CPU0_AG40"
$PN"AG40"5;
"VDDCR_CPU0_AG41"
$PN"AG41"5;
"VDDCR_CPU0_AK23"
$PN"AK23"5;
"VDDCR_CPU0_AK24"
$PN"AK24"5;
"VDDCR_CPU0_AK26"
$PN"AK26"5;
"VDDCR_CPU0_AK27"
$PN"AK27"5;
"VDDCR_CPU0_AK29"
$PN"AK29"5;
"VDDCR_CPU0_AK30"
$PN"AK30"5;
"VDDCR_CPU0_AK32"
$PN"AK32"5;
"VDDCR_CPU0_AK33"
$PN"AK33"5;
"VDDCR_CPU0_AK43"
$PN"AK43"5;
"VDDCR_CPU0_AK44"
$PN"AK44"5;
"VDDCR_CPU0_AK46"
$PN"AK46"5;
"VDDCR_CPU0_AK47"
$PN"AK47"5;
"VDDCR_CPU0_AK49"
$PN"AK49"5;
"VDDCR_CPU0_AK50"
$PN"AK50"5;
"VDDCR_CPU0_AK52"
$PN"AK52"5;
"VDDCR_CPU0_AK53"
$PN"AK53"5;
"VDDCR_CPU0_AL35"
$PN"AL35"5;
"VDDCR_CPU0_AL36"
$PN"AL36"5;
"VDDCR_CPU0_AL40"
$PN"AL40"5;
"VDDCR_CPU0_AL41"
$PN"AL41"5;
"VDDCR_CPU0_AP23"
$PN"AP23"5;
"VDDCR_CPU0_AP24"
$PN"AP24"5;
"VDDCR_CPU0_AP26"
$PN"AP26"5;
"VDDCR_CPU0_AP27"
$PN"AP27"5;
"VDDCR_CPU0_AP29"
$PN"AP29"5;
"VDDCR_CPU0_AP30"
$PN"AP30"5;
"VDDCR_CPU0_AP32"
$PN"AP32"5;
"VDDCR_CPU0_AP33"
$PN"AP33"5;
"VDDCR_CPU0_AP43"
$PN"AP43"5;
"VDDCR_CPU0_AP44"
$PN"AP44"5;
"VDDCR_CPU0_AP46"
$PN"AP46"5;
"VDDCR_CPU0_AP47"
$PN"AP47"5;
"VDDCR_CPU0_AP49"
$PN"AP49"5;
"VDDCR_CPU0_AP50"
$PN"AP50"5;
"VDDCR_CPU0_AP52"
$PN"AP52"5;
"VDDCR_CPU0_AP53"
$PN"AP53"5;
"VDDCR_CPU0_AR23"
$PN"AR23"5;
"VDDCR_CPU0_AR25"
$PN"AR25"5;
"VDDCR_CPU0_AR27"
$PN"AR27"5;
"VDDCR_CPU0_AR29"
$PN"AR29"5;
"VDDCR_CPU0_AR31"
$PN"AR31"5;
"VDDCR_CPU0_AR33"
$PN"AR33"5;
"VDDCR_CPU0_AR35"
$PN"AR35"5;
"VDDCR_CPU0_AR40"
$PN"AR40"5;
"VDDCR_CPU0_AR42"
$PN"AR42"5;
"VDDCR_CPU0_AR44"
$PN"AR44"5;
"VDDCR_CPU0_AR46"
$PN"AR46"5;
"VDDCR_CPU0_AR48"
$PN"AR48"5;
"VDDCR_CPU0_AR50"
$PN"AR50"5;
"VDDCR_CPU0_AT24"
$PN"AT24"5;
"VDDCR_CPU0_AT26"
$PN"AT26"5;
"VDDCR_CPU0_AT28"
$PN"AT28"5;
"VDDCR_CPU0_AT30"
$PN"AT30"5;
"VDDCR_CPU0_AT32"
$PN"AT32"5;
"VDDCR_CPU0_AT34"
$PN"AT34"5;
"VDDCR_CPU0_AT36"
$PN"AT36"5;
"VDDCR_CPU0_AT39"
$PN"AT39"5;
"VDDCR_CPU0_AT41"
$PN"AT41"5;
"VDDCR_CPU0_AT43"
$PN"AT43"5;
"VDDCR_CPU0_AT45"
$PN"AT45"5;
"VDDCR_CPU0_AT47"
$PN"AT47"5;
"VDDCR_CPU0_B19"
$PN"B19"4;
"VDDCR_CPU0_B20"
$PN"B20"4;
"VDDCR_CPU0_B22"
$PN"B22"4;
"VDDCR_CPU0_B23"
$PN"B23"4;
"VDDCR_CPU0_B25"
$PN"B25"4;
"VDDCR_CPU0_B26"
$PN"B26"4;
"VDDCR_CPU0_B28"
$PN"B28"4;
"VDDCR_CPU0_B29"
$PN"B29"4;
"VDDCR_CPU0_B31"
$PN"B31"4;
"VDDCR_CPU0_B32"
$PN"B32"4;
"VDDCR_CPU0_B34"
$PN"B34"4;
"VDDCR_CPU0_B35"
$PN"B35"4;
"VDDCR_CPU0_B41"
$PN"B41"4;
"VDDCR_CPU0_B42"
$PN"B42"4;
"VDDCR_CPU0_B44"
$PN"B44"4;
"VDDCR_CPU0_B45"
$PN"B45"4;
"VDDCR_CPU0_B47"
$PN"B47"4;
"VDDCR_CPU0_B48"
$PN"B48"4;
"VDDCR_CPU0_B50"
$PN"B50"4;
"VDDCR_CPU0_B51"
$PN"B51"4;
"VDDCR_CPU0_B53"
$PN"B53"4;
"VDDCR_CPU0_B54"
$PN"B54"4;
"VDDCR_CPU0_B56"
$PN"B56"4;
"VDDCR_CPU0_B57"
$PN"B57"4;
"VDDCR_CPU0_C20"
$PN"C20"4;
"VDDCR_CPU0_D55"
$PN"D55"4;
"VDDCR_CPU0_D56"
$PN"D56"4;
"VDDCR_CPU0_E22"
$PN"E22"4;
"VDDCR_CPU0_E25"
$PN"E25"4;
"VDDCR_CPU0_E28"
$PN"E28"4;
"VDDCR_CPU0_E31"
$PN"E31"4;
"VDDCR_CPU0_E34"
$PN"E34"4;
"VDDCR_CPU0_E35"
$PN"E35"4;
"VDDCR_CPU0_E42"
$PN"E42"4;
"VDDCR_CPU0_E45"
$PN"E45"4;
"VDDCR_CPU0_E48"
$PN"E48"4;
"VDDCR_CPU0_E51"
$PN"E51"4;
"VDDCR_CPU0_E54"
$PN"E54"4;
"VDDCR_CPU0_F22"
$PN"F22"4;
"VDDCR_CPU0_F25"
$PN"F25"4;
"VDDCR_CPU0_F28"
$PN"F28"4;
"VDDCR_CPU0_F31"
$PN"F31"4;
"VDDCR_CPU0_F34"
$PN"F34"4;
"VDDCR_CPU0_F42"
$PN"F42"4;
"VDDCR_CPU0_F45"
$PN"F45"4;
"VDDCR_CPU0_F48"
$PN"F48"4;
"VDDCR_CPU0_F51"
$PN"F51"4;
"VDDCR_CPU0_F54"
$PN"F54"4;
"VDDCR_CPU0_G35"
$PN"G35"4;
"VDDCR_CPU0_G36"
$PN"G36"4;
"VDDCR_CPU0_G40"
$PN"G40"4;
"VDDCR_CPU0_G41"
$PN"G41"4;
"VDDCR_CPU0_H23"
$PN"H23"4;
"VDDCR_CPU0_H24"
$PN"H24"4;
"VDDCR_CPU0_H26"
$PN"H26"4;
"VDDCR_CPU0_H27"
$PN"H27"4;
"VDDCR_CPU0_H29"
$PN"H29"4;
"VDDCR_CPU0_H30"
$PN"H30"4;
"VDDCR_CPU0_H32"
$PN"H32"4;
"VDDCR_CPU0_H33"
$PN"H33"4;
"VDDCR_CPU0_H43"
$PN"H43"4;
"VDDCR_CPU0_H44"
$PN"H44"4;
"VDDCR_CPU0_H46"
$PN"H46"4;
"VDDCR_CPU0_H47"
$PN"H47"4;
"VDDCR_CPU0_H49"
$PN"H49"4;
"VDDCR_CPU0_H50"
$PN"H50"4;
"VDDCR_CPU0_H52"
$PN"H52"4;
"VDDCR_CPU0_H53"
$PN"H53"4;
"VDDCR_CPU0_J35"
$PN"J35"4;
"VDDCR_CPU0_J36"
$PN"J36"4;
"VDDCR_CPU0_J40"
$PN"J40"4;
"VDDCR_CPU0_J41"
$PN"J41"4;
"VDDCR_CPU0_M23"
$PN"M23"4;
"VDDCR_CPU0_M24"
$PN"M24"4;
"VDDCR_CPU0_M26"
$PN"M26"4;
"VDDCR_CPU0_M27"
$PN"M27"4;
"VDDCR_CPU0_M29"
$PN"M29"4;
"VDDCR_CPU0_M30"
$PN"M30"4;
"VDDCR_CPU0_M32"
$PN"M32"4;
"VDDCR_CPU0_M33"
$PN"M33"4;
"VDDCR_CPU0_M43"
$PN"M43"4;
"VDDCR_CPU0_M44"
$PN"M44"4;
"VDDCR_CPU0_M46"
$PN"M46"4;
"VDDCR_CPU0_M47"
$PN"M47"4;
"VDDCR_CPU0_M49"
$PN"M49"4;
"VDDCR_CPU0_M50"
$PN"M50"4;
"VDDCR_CPU0_M52"
$PN"M52"4;
"VDDCR_CPU0_M53"
$PN"M53"4;
"VDDCR_CPU0_N35"
$PN"N35"4;
"VDDCR_CPU0_N36"
$PN"N36"4;
"VDDCR_CPU0_N40"
$PN"N40"4;
"VDDCR_CPU0_N41"
$PN"N41"4;
"VDDCR_CPU0_T23"
$PN"T23"4;
"VDDCR_CPU0_T24"
$PN"T24"4;
"VDDCR_CPU0_T26"
$PN"T26"4;
"VDDCR_CPU0_T27"
$PN"T27"4;
"VDDCR_CPU0_T29"
$PN"T29"4;
"VDDCR_CPU0_T30"
$PN"T30"4;
"VDDCR_CPU0_T32"
$PN"T32"4;
"VDDCR_CPU0_T33"
$PN"T33"4;
"VDDCR_CPU0_T43"
$PN"T43"4;
"VDDCR_CPU0_T44"
$PN"T44"4;
"VDDCR_CPU0_T46"
$PN"T46"4;
"VDDCR_CPU0_T47"
$PN"T47"4;
"VDDCR_CPU0_T49"
$PN"T49"4;
"VDDCR_CPU0_T50"
$PN"T50"4;
"VDDCR_CPU0_T52"
$PN"T52"4;
"VDDCR_CPU0_T53"
$PN"T53"4;
"VDDCR_CPU0_U35"
$PN"U35"4;
"VDDCR_CPU0_U36"
$PN"U36"4;
"VDDCR_CPU0_U40"
$PN"U40"4;
"VDDCR_CPU0_U41"
$PN"U41"4;
"VDDCR_CPU0_W29"
$PN"W29"4;
"VDDCR_CPU0_W30"
$PN"W30"4;
"VDDCR_CPU0_W32"
$PN"W32"4;
"VDDCR_CPU0_W33"
$PN"W33"4;
"VDDCR_CPU0_W43"
$PN"W43"5;
"VDDCR_CPU0_W44"
$PN"W44"5;
"VDDCR_CPU0_W46"
$PN"W46"5;
"VDDCR_CPU0_W47"
$PN"W47"5;
%"VCC_CORE"
"1","(-5525,6550)","0","pure_quanta_power","I30";
;
HDL_POWER"PVDDCR_CPU1_P1"
CDS_LIB"pure_quanta_power";
"A"7;
%"VCC_CORE"
"1","(-6950,6325)","0","pure_quanta_power","I31";
;
HDL_POWER"PVDDCR_CPU1_P1"
CDS_LIB"pure_quanta_power";
"A"6;
%"GENOA_SP5"
"25","(-6225,3375)","0","pure_quanta","I32";
;
LOCATION"U26"
$SEC"25"
CDS_SEC"25"
PART_TYPE"SMLF"
PART_NUMBER"DGA^6000030"
MATERIAL"IO"
VALUE"SOCKET6096_13568-001"
CDS_LIB"pure_quanta"
CDS_LMAN_SYM_OUTLINE"-500,3200,500,-3200"
NEEDS_NO_SIZE"TRUE";
"VDDCR_CPU1_BN46"
$PN"BN46"7;
"VDDCR_CPU1_BN35"
$PN"BN35"7;
"VDDCR_CPU1_BN27"
$PN"BN27"7;
"VDDCR_CPU1_BP32"
$PN"BP32"7;
"VDDCR_CPU1_BP28"
$PN"BP28"7;
"VDDCR_CPU1_BP24"
$PN"BP24"7;
"VDDCR_CPU1_DH51"
$PN"DH51"7;
"VDDCR_CPU1_DH50"
$PN"DH50"7;
"VDDCR_CPU1_DH48"
$PN"DH48"7;
"VDDCR_CPU1_DH47"
$PN"DH47"7;
"VDDCR_CPU1_DH45"
$PN"DH45"7;
"VDDCR_CPU1_DH57"
$PN"DH57"7;
"VDDCR_CPU1_DH56"
$PN"DH56"7;
"VDDCR_CPU1_DH54"
$PN"DH54"7;
"VDDCR_CPU1_DH53"
$PN"DH53"7;
"VDDCR_CPU1_DH44"
$PN"DH44"7;
"VDDCR_CPU1_DH42"
$PN"DH42"7;
"VDDCR_CPU1_DH41"
$PN"DH41"7;
"VDDCR_CPU1_DH35"
$PN"DH35"7;
"VDDCR_CPU1_DH34"
$PN"DH34"7;
"VDDCR_CPU1_DH32"
$PN"DH32"7;
"VDDCR_CPU1_DH31"
$PN"DH31"7;
"VDDCR_CPU1_DH29"
$PN"DH29"7;
"VDDCR_CPU1_DH28"
$PN"DH28"7;
"VDDCR_CPU1_DH26"
$PN"DH26"7;
"VDDCR_CPU1_DH25"
$PN"DH25"7;
"VDDCR_CPU1_DH23"
$PN"DH23"7;
"VDDCR_CPU1_DH22"
$PN"DH22"7;
"VDDCR_CPU1_DH20"
$PN"DH20"7;
"VDDCR_CPU1_DH19"
$PN"DH19"7;
"VDDCR_CPU1_DG57"
$PN"DG57"7;
"VDDCR_CPU1_DG19"
$PN"DG19"7;
"VDDCR_CPU1_DE54"
$PN"DE54"7;
"VDDCR_CPU1_DE51"
$PN"DE51"7;
"VDDCR_CPU1_DE48"
$PN"DE48"7;
"VDDCR_CPU1_DE45"
$PN"DE45"7;
"VDDCR_CPU1_DE42"
$PN"DE42"7;
"VDDCR_CPU1_DE41"
$PN"DE41"7;
"VDDCR_CPU1_DE35"
$PN"DE35"7;
"VDDCR_CPU1_DE34"
$PN"DE34"7;
"VDDCR_CPU1_DE31"
$PN"DE31"7;
"VDDCR_CPU1_DE28"
$PN"DE28"7;
"VDDCR_CPU1_DE25"
$PN"DE25"7;
"VDDCR_CPU1_DE22"
$PN"DE22"7;
"VDDCR_CPU1_DD54"
$PN"DD54"7;
"VDDCR_CPU1_DD51"
$PN"DD51"7;
"VDDCR_CPU1_DD48"
$PN"DD48"7;
"VDDCR_CPU1_DD45"
$PN"DD45"7;
"VDDCR_CPU1_DD42"
$PN"DD42"7;
"VDDCR_CPU1_DD34"
$PN"DD34"7;
"VDDCR_CPU1_DD31"
$PN"DD31"7;
"VDDCR_CPU1_DD28"
$PN"DD28"7;
"VDDCR_CPU1_DD25"
$PN"DD25"7;
"VDDCR_CPU1_DD22"
$PN"DD22"7;
"VDDCR_CPU1_DC41"
$PN"DC41"7;
"VDDCR_CPU1_DC40"
$PN"DC40"7;
"VDDCR_CPU1_DC36"
$PN"DC36"7;
"VDDCR_CPU1_DC35"
$PN"DC35"7;
"VDDCR_CPU1_DB53"
$PN"DB53"7;
"VDDCR_CPU1_DB52"
$PN"DB52"7;
"VDDCR_CPU1_DB50"
$PN"DB50"7;
"VDDCR_CPU1_DB49"
$PN"DB49"7;
"VDDCR_CPU1_DB47"
$PN"DB47"7;
"VDDCR_CPU1_DB46"
$PN"DB46"7;
"VDDCR_CPU1_DB44"
$PN"DB44"7;
"VDDCR_CPU1_DB43"
$PN"DB43"7;
"VDDCR_CPU1_DB33"
$PN"DB33"7;
"VDDCR_CPU1_DB32"
$PN"DB32"7;
"VDDCR_CPU1_DB30"
$PN"DB30"7;
"VDDCR_CPU1_DB29"
$PN"DB29"7;
"VDDCR_CPU1_DB27"
$PN"DB27"7;
"VDDCR_CPU1_DB26"
$PN"DB26"7;
"VDDCR_CPU1_DB24"
$PN"DB24"7;
"VDDCR_CPU1_DB23"
$PN"DB23"7;
"VDDCR_CPU1_DA41"
$PN"DA41"7;
"VDDCR_CPU1_DA40"
$PN"DA40"7;
"VDDCR_CPU1_DA36"
$PN"DA36"7;
"VDDCR_CPU1_DA35"
$PN"DA35"7;
"VDDCR_CPU1_CV53"
$PN"CV53"7;
"VDDCR_CPU1_CV52"
$PN"CV52"7;
"VDDCR_CPU1_CV50"
$PN"CV50"7;
"VDDCR_CPU1_CV49"
$PN"CV49"7;
"VDDCR_CPU1_CV47"
$PN"CV47"7;
"VDDCR_CPU1_CV46"
$PN"CV46"7;
"VDDCR_CPU1_CV44"
$PN"CV44"7;
"VDDCR_CPU1_CV43"
$PN"CV43"7;
"VDDCR_CPU1_CV33"
$PN"CV33"7;
"VDDCR_CPU1_CV32"
$PN"CV32"7;
"VDDCR_CPU1_CV30"
$PN"CV30"7;
"VDDCR_CPU1_CV29"
$PN"CV29"7;
"VDDCR_CPU1_CV27"
$PN"CV27"7;
"VDDCR_CPU1_CV26"
$PN"CV26"7;
"VDDCR_CPU1_CV24"
$PN"CV24"7;
"VDDCR_CPU1_CV23"
$PN"CV23"7;
"VDDCR_CPU1_CU41"
$PN"CU41"7;
"VDDCR_CPU1_CU40"
$PN"CU40"7;
"VDDCR_CPU1_CU36"
$PN"CU36"7;
"VDDCR_CPU1_CU35"
$PN"CU35"7;
"VDDCR_CPU1_CP53"
$PN"CP53"7;
"VDDCR_CPU1_CP52"
$PN"CP52"7;
"VDDCR_CPU1_CP50"
$PN"CP50"7;
"VDDCR_CPU1_CP49"
$PN"CP49"7;
"VDDCR_CPU1_CP47"
$PN"CP47"7;
"VDDCR_CPU1_CP46"
$PN"CP46"7;
"VDDCR_CPU1_CP44"
$PN"CP44"7;
"VDDCR_CPU1_CP43"
$PN"CP43"7;
"VDDCR_CPU1_CP33"
$PN"CP33"7;
"VDDCR_CPU1_CP32"
$PN"CP32"7;
"VDDCR_CPU1_CP30"
$PN"CP30"7;
"VDDCR_CPU1_CP29"
$PN"CP29"7;
"VDDCR_CPU1_CP27"
$PN"CP27"7;
"VDDCR_CPU1_CP26"
$PN"CP26"7;
"VDDCR_CPU1_CP24"
$PN"CP24"7;
"VDDCR_CPU1_CP23"
$PN"CP23"7;
"VDDCR_CPU1_CN41"
$PN"CN41"7;
"VDDCR_CPU1_CN40"
$PN"CN40"7;
"VDDCR_CPU1_CN36"
$PN"CN36"7;
"VDDCR_CPU1_CN35"
$PN"CN35"7;
"VDDCR_CPU1_CL47"
$PN"CL47"7;
"VDDCR_CPU1_CL46"
$PN"CL46"7;
"VDDCR_CPU1_CL44"
$PN"CL44"7;
"VDDCR_CPU1_CL43"
$PN"CL43"7;
"VDDCR_CPU1_CL33"
$PN"CL33"7;
"VDDCR_CPU1_CL32"
$PN"CL32"7;
"VDDCR_CPU1_CL30"
$PN"CL30"6;
"VDDCR_CPU1_CL29"
$PN"CL29"6;
"VDDCR_CPU1_CK41"
$PN"CK41"6;
"VDDCR_CPU1_CK40"
$PN"CK40"6;
"VDDCR_CPU1_CK36"
$PN"CK36"6;
"VDDCR_CPU1_CK35"
$PN"CK35"6;
"VDDCR_CPU1_CH53"
$PN"CH53"6;
"VDDCR_CPU1_CH52"
$PN"CH52"6;
"VDDCR_CPU1_CH50"
$PN"CH50"6;
"VDDCR_CPU1_CH49"
$PN"CH49"6;
"VDDCR_CPU1_CH47"
$PN"CH47"6;
"VDDCR_CPU1_CH46"
$PN"CH46"6;
"VDDCR_CPU1_CH44"
$PN"CH44"6;
"VDDCR_CPU1_CH43"
$PN"CH43"6;
"VDDCR_CPU1_CH33"
$PN"CH33"6;
"VDDCR_CPU1_CH32"
$PN"CH32"6;
"VDDCR_CPU1_CH30"
$PN"CH30"6;
"VDDCR_CPU1_CH29"
$PN"CH29"6;
"VDDCR_CPU1_CH27"
$PN"CH27"6;
"VDDCR_CPU1_CH26"
$PN"CH26"6;
"VDDCR_CPU1_CH24"
$PN"CH24"6;
"VDDCR_CPU1_CH23"
$PN"CH23"6;
"VDDCR_CPU1_CG41"
$PN"CG41"6;
"VDDCR_CPU1_CG40"
$PN"CG40"6;
"VDDCR_CPU1_CG36"
$PN"CG36"6;
"VDDCR_CPU1_CG35"
$PN"CG35"6;
"VDDCR_CPU1_CD53"
$PN"CD53"6;
"VDDCR_CPU1_CD52"
$PN"CD52"6;
"VDDCR_CPU1_CD50"
$PN"CD50"6;
"VDDCR_CPU1_CD49"
$PN"CD49"6;
"VDDCR_CPU1_CD47"
$PN"CD47"6;
"VDDCR_CPU1_CD46"
$PN"CD46"6;
"VDDCR_CPU1_CD44"
$PN"CD44"6;
"VDDCR_CPU1_CD43"
$PN"CD43"6;
"VDDCR_CPU1_CD33"
$PN"CD33"6;
"VDDCR_CPU1_CD32"
$PN"CD32"6;
"VDDCR_CPU1_CD30"
$PN"CD30"6;
"VDDCR_CPU1_CD29"
$PN"CD29"6;
"VDDCR_CPU1_CD27"
$PN"CD27"6;
"VDDCR_CPU1_CD26"
$PN"CD26"6;
"VDDCR_CPU1_CD24"
$PN"CD24"6;
"VDDCR_CPU1_CD23"
$PN"CD23"6;
"VDDCR_CPU1_CC41"
$PN"CC41"6;
"VDDCR_CPU1_CC40"
$PN"CC40"6;
"VDDCR_CPU1_CC36"
$PN"CC36"6;
"VDDCR_CPU1_CC35"
$PN"CC35"6;
"VDDCR_CPU1_BY53"
$PN"BY53"6;
"VDDCR_CPU1_BY52"
$PN"BY52"6;
"VDDCR_CPU1_BY50"
$PN"BY50"6;
"VDDCR_CPU1_BY49"
$PN"BY49"6;
"VDDCR_CPU1_BY47"
$PN"BY47"6;
"VDDCR_CPU1_BY46"
$PN"BY46"6;
"VDDCR_CPU1_BY44"
$PN"BY44"6;
"VDDCR_CPU1_BY43"
$PN"BY43"6;
"VDDCR_CPU1_BY33"
$PN"BY33"6;
"VDDCR_CPU1_BY32"
$PN"BY32"6;
"VDDCR_CPU1_BY30"
$PN"BY30"6;
"VDDCR_CPU1_BY29"
$PN"BY29"6;
"VDDCR_CPU1_BY27"
$PN"BY27"6;
"VDDCR_CPU1_BY26"
$PN"BY26"6;
"VDDCR_CPU1_BY24"
$PN"BY24"6;
"VDDCR_CPU1_BY23"
$PN"BY23"6;
"VDDCR_CPU1_BW41"
$PN"BW41"6;
"VDDCR_CPU1_BW40"
$PN"BW40"6;
"VDDCR_CPU1_BW36"
$PN"BW36"6;
"VDDCR_CPU1_BW35"
$PN"BW35"6;
"VDDCR_CPU1_BT53"
$PN"BT53"6;
"VDDCR_CPU1_BT52"
$PN"BT52"6;
"VDDCR_CPU1_BT50"
$PN"BT50"6;
"VDDCR_CPU1_BT49"
$PN"BT49"6;
"VDDCR_CPU1_BT47"
$PN"BT47"6;
"VDDCR_CPU1_BT46"
$PN"BT46"6;
"VDDCR_CPU1_BT44"
$PN"BT44"6;
"VDDCR_CPU1_BT43"
$PN"BT43"6;
"VDDCR_CPU1_BT33"
$PN"BT33"6;
"VDDCR_CPU1_BT32"
$PN"BT32"6;
"VDDCR_CPU1_BT30"
$PN"BT30"6;
"VDDCR_CPU1_BT29"
$PN"BT29"6;
"VDDCR_CPU1_BT27"
$PN"BT27"6;
"VDDCR_CPU1_BT26"
$PN"BT26"6;
"VDDCR_CPU1_BT24"
$PN"BT24"6;
"VDDCR_CPU1_BT23"
$PN"BT23"6;
"VDDCR_CPU1_BR52"
$PN"BR52"6;
"VDDCR_CPU1_BR50"
$PN"BR50"6;
"VDDCR_CPU1_BR48"
$PN"BR48"6;
"VDDCR_CPU1_BR46"
$PN"BR46"6;
"VDDCR_CPU1_BR44"
$PN"BR44"6;
"VDDCR_CPU1_BR42"
$PN"BR42"6;
"VDDCR_CPU1_BR40"
$PN"BR40"6;
"VDDCR_CPU1_BR35"
$PN"BR35"6;
"VDDCR_CPU1_BR33"
$PN"BR33"6;
"VDDCR_CPU1_BR31"
$PN"BR31"6;
"VDDCR_CPU1_BR29"
$PN"BR29"6;
"VDDCR_CPU1_BR27"
$PN"BR27"6;
"VDDCR_CPU1_BR25"
$PN"BR25"6;
"VDDCR_CPU1_BR23"
$PN"BR23"6;
"VDDCR_CPU1_BP49"
$PN"BP49"6;
"VDDCR_CPU1_BP47"
$PN"BP47"6;
"VDDCR_CPU1_BP45"
$PN"BP45"6;
"VDDCR_CPU1_BP43"
$PN"BP43"6;
"VDDCR_CPU1_BP41"
$PN"BP41"6;
"VDDCR_CPU1_BP39"
$PN"BP39"6;
"VDDCR_CPU1_BP36"
$PN"BP36"6;
"VDDCR_CPU1_BP34"
$PN"BP34"6;
"VDDCR_CPU1_BP30"
$PN"BP30"6;
"VDDCR_CPU1_BP26"
$PN"BP26"6;
"VDDCR_CPU1_BN50"
$PN"BN50"6;
"VDDCR_CPU1_BN42"
$PN"BN42"6;
"VDDCR_CPU1_BN31"
$PN"BN31"6;
%"VCC_CORE"
"1","(-2050,6575)","0","pure_quanta_power","I36";
;
HDL_POWER"PVDDIO_P1"
CDS_LIB"pure_quanta_power";
"A"3;
%"UNIVERSAL_POWER"
"1","(-1125,950)","0","pure_quanta_power","I37";
;
HDL_POWER"PVDD18_S5_P1"
CDS_LIB"pure_quanta_power";
"A"1;
%"UNIVERSAL_POWER"
"1","(-1450,950)","0","pure_quanta_power","I38";
;
HDL_POWER"P1V5_BAT"
CDS_LIB"pure_quanta_power";
"A"2;
%"VCC_CORE"
"1","(-3550,6575)","0","pure_quanta_power","I41";
;
HDL_POWER"PVDD11_S3_P1"
CDS_LIB"pure_quanta_power";
"A"11;
%"UNIVERSAL_POWER"
"1","(-3725,2700)","0","pure_quanta_power","I42";
;
HDL_POWER"PVDD18_S5_P1"
CDS_LIB"pure_quanta_power";
"A"10;
%"UNIVERSAL_POWER"
"1","(-3725,1050)","0","pure_quanta_power","I44";
;
HDL_POWER"PVDD_33_S5"
CDS_LIB"pure_quanta_power";
"A"9;
%"GENOA_SP5"
"27","(-2800,3500)","0","pure_quanta","I45";
;
LOCATION"U26"
$SEC"27"
CDS_SEC"27"
MATERIAL"IO"
PART_TYPE"SMLF"
PART_NUMBER"DGA^6000030"
VALUE"SOCKET6096_13568-001"
CDS_LIB"pure_quanta"
CDS_LMAN_SYM_OUTLINE"-500,3075,500,-3075"
NEEDS_NO_SIZE"TRUE";
"VDD_11_S3_CT19"
$PN"CT19"11;
"VDD_11_S3_CT22"
$PN"CT22"11;
"VDD_11_S3_CW4"
$PN"CW4"11;
"VDD_11_S3_CW11"
$PN"CW11"11;
"VDD_11_S3_CW18"
$PN"CW18"11;
"VDD_11_S3_CY22"
$PN"CY22"11;
"VDD_11_S3_DB5"
$PN"DB5"11;
"VDD_11_S3_DB12"
$PN"DB12"11;
"VDD_11_S3_DB19"
$PN"DB19"11;
"VDD_11_S3_DE4"
$PN"DE4"11;
"VDD_11_S3_DE11"
$PN"DE11"11;
"VDD_11_S3_DE18"
$PN"DE18"11;
"VDD_11_S3_DG5"
$PN"DG5"11;
"VDDIO_CT64"
$PN"CT64"3;
"VDDIO_CT71"
$PN"CT71"3;
"VDDIO_CW58"
$PN"CW58"3;
"VDDIO_CW65"
$PN"CW65"3;
"VDDIO_CW72"
$PN"CW72"3;
"VDDIO_CY54"
$PN"CY54"3;
"VDDIO_DB57"
$PN"DB57"3;
"VDDIO_DB64"
$PN"DB64"3;
"VDDIO_DB71"
$PN"DB71"3;
"VDDIO_DE58"
$PN"DE58"3;
"VDDIO_DE65"
$PN"DE65"3;
"VDDIO_DE72"
$PN"DE72"3;
"VDDIO_DG64"
$PN"DG64"3;
"VDDIO_DG71"
$PN"DG71"3;
"VDDBT_RTC_G"
$PN"BN23"13;
"VDDIO_AUDIO"
$PN"BH27"10;
"VDD_33_S5_BP51"
$PN"BP51"9;
"VDD_33_S5_BN52"
$PN"BN52"9;
"VDD_11_S3_CT12"
$PN"CT12"11;
"VDD_18_S5_BB53"
$PN"BB53"10;
"VDD_18_S5_BB51"
$PN"BB51"10;
"VDD_18_S5_BA54"
$PN"BA54"10;
"VDD_18_S5_BA52"
$PN"BA52"10;
"VDD_18_S5_BA50"
$PN"BA50"10;
"VDD_18_S5_AY53"
$PN"AY53"10;
"VDD_18_S5_AY51"
$PN"AY51"10;
"VDD_18_S5_AW54"
$PN"AW54"10;
"VDD_18_S5_AW52"
$PN"AW52"10;
"VDD_18_S5_BC54"
$PN"BC54"10;
"VDD_18_S5_BC52"
$PN"BC52"10;
"VDD_18_S5_AW50"
$PN"AW50"10;
"VDD_18_S5_AV53"
$PN"AV53"10;
"VDD_18_S5_AV51"
$PN"AV51"10;
"VDD_18_S5_AV49"
$PN"AV49"10;
"VDD_18_S5_AU52"
$PN"AU52"10;
"VDD_18_S5_AU50"
$PN"AU50"10;
"VDD_18_S5_AT53"
$PN"AT53"10;
"VDD_18_S5_AT51"
$PN"AT51"10;
"VDD_18_S5_AR54"
$PN"AR54"10;
"VDD_18_S5_AR52"
$PN"AR52"10;
"VDD_18_S5_AU54"
$PN"AU54"10;
"VDD_11_S3_CT5"
$PN"CT5"11;
"VDD_11_S3_CN18"
$PN"CN18"11;
"VDD_11_S3_CN11"
$PN"CN11"11;
"VDD_11_S3_CN4"
$PN"CN4"11;
"VDD_11_S3_CM22"
$PN"CM22"11;
"VDD_11_S3_CK19"
$PN"CK19"11;
"VDD_11_S3_CK12"
$PN"CK12"11;
"VDD_11_S3_CK5"
$PN"CK5"11;
"VDD_11_S3_CJ22"
$PN"CJ22"11;
"VDD_11_S3_CG18"
$PN"CG18"11;
"VDD_11_S3_CG11"
$PN"CG11"11;
"VDD_11_S3_CG4"
$PN"CG4"11;
"VDD_11_S3_CF22"
$PN"CF22"11;
"VDD_11_S3_CD19"
$PN"CD19"11;
"VDD_11_S3_CD12"
$PN"CD12"11;
"VDD_11_S3_CD5"
$PN"CD5"11;
"VDD_11_S3_CB22"
$PN"CB22"11;
"VDD_11_S3_CA18"
$PN"CA18"11;
"VDD_11_S3_CA11"
$PN"CA11"11;
"VDD_11_S3_CA4"
$PN"CA4"11;
"VDD_11_S3_BV22"
$PN"BV22"11;
"VDD_11_S3_BV19"
$PN"BV19"11;
"VDD_11_S3_BV12"
$PN"BV12"11;
"VDD_11_S3_BV5"
$PN"BV5"11;
"VDD_11_S3_BR18"
$PN"BR18"11;
"VDD_11_S3_BR11"
$PN"BR11"11;
"VDD_11_S3_BR4"
$PN"BR4"11;
"VDD_11_S3_BP22"
$PN"BP22"11;
"VDD_11_S3_BN48"
$PN"BN48"11;
"VDD_11_S3_BN44"
$PN"BN44"11;
"VDD_11_S3_BN40"
$PN"BN40"11;
"VDD_11_S3_BN33"
$PN"BN33"11;
"VDD_11_S3_BN29"
$PN"BN29"11;
"VDD_11_S3_BN25"
$PN"BN25"11;
"VDD_11_S3_BM49"
$PN"BM49"11;
"VDD_11_S3_BM47"
$PN"BM47"11;
"VDD_11_S3_BM45"
$PN"BM45"11;
"VDD_11_S3_BM43"
$PN"BM43"11;
"VDD_11_S3_BM41"
$PN"BM41"11;
"VDD_11_S3_BM39"
$PN"BM39"11;
"VDD_11_S3_BM36"
$PN"BM36"11;
"VDD_11_S3_BM34"
$PN"BM34"11;
"VDD_11_S3_BM32"
$PN"BM32"11;
"VDD_11_S3_BM30"
$PN"BM30"11;
"VDD_11_S3_BM28"
$PN"BM28"11;
"VDD_11_S3_BM26"
$PN"BM26"11;
"VDD_11_S3_BM24"
$PN"BM24"11;
"VDD_11_S3_BM22"
$PN"BM22"11;
"VDD_11_S3_BM19"
$PN"BM19"11;
"VDD_11_S3_BM12"
$PN"BM12"11;
"VDD_11_S3_BL48"
$PN"BL48"11;
"VDD_11_S3_BL27"
$PN"BL27"11;
"VDD_11_S3_BL25"
$PN"BL25"11;
"VDD_11_S3_BL23"
$PN"BL23"11;
"VDD_11_S3_BK49"
$PN"BK49"11;
"VDD_11_S3_BK28"
$PN"BK28"11;
"VDD_11_S3_BK26"
$PN"BK26"11;
"VDD_11_S3_BK24"
$PN"BK24"11;
"VDD_11_S3_BK22"
$PN"BK22"11;
"VDD_11_S3_BJ27"
$PN"BJ27"11;
"VDD_11_S3_BJ25"
$PN"BJ25"11;
"VDD_11_S3_BJ23"
$PN"BJ23"11;
"VDD_11_S3_BJ18"
$PN"BJ18"11;
"VDDIO_CT57"
$PN"CT57"3;
"VDDIO_CT54"
$PN"CT54"3;
"VDDIO_CN72"
$PN"CN72"3;
"VDDIO_CN65"
$PN"CN65"3;
"VDDIO_CN58"
$PN"CN58"3;
"VDDIO_CM54"
$PN"CM54"3;
"VDDIO_CK71"
$PN"CK71"3;
"VDDIO_CK64"
$PN"CK64"3;
"VDDIO_CK57"
$PN"CK57"3;
"VDDIO_CJ54"
$PN"CJ54"3;
"VDDIO_CG72"
$PN"CG72"3;
"VDDIO_CG65"
$PN"CG65"3;
"VDDIO_CG58"
$PN"CG58"3;
"VDDIO_CF54"
$PN"CF54"3;
"VDDIO_CD71"
$PN"CD71"3;
"VDDIO_CD64"
$PN"CD64"3;
"VDDIO_CD57"
$PN"CD57"3;
"VDDIO_CB54"
$PN"CB54"3;
"VDDIO_CA72"
$PN"CA72"3;
"VDDIO_CA65"
$PN"CA65"3;
"VDDIO_CA58"
$PN"CA58"3;
"VDDIO_BV71"
$PN"BV71"3;
"VDDIO_BV64"
$PN"BV64"3;
"VDDIO_BV57"
$PN"BV57"3;
"VDDIO_BV54"
$PN"BV54"3;
"VDDIO_BR72"
$PN"BR72"3;
"VDDIO_BR65"
$PN"BR65"3;
"VDDIO_BR58"
$PN"BR58"3;
"VDDIO_BN54"
$PN"BN54"3;
"VDDIO_BM71"
$PN"BM71"3;
"VDDIO_BM64"
$PN"BM64"3;
"VDDIO_BM57"
$PN"BM57"3;
"VDDIO_BM53"
$PN"BM53"3;
"VDDIO_BM51"
$PN"BM51"3;
"VDDIO_BL54"
$PN"BL54"3;
"VDDIO_BL52"
$PN"BL52"3;
"VDDIO_BL50"
$PN"BL50"3;
"VDDIO_BK53"
$PN"BK53"3;
"VDDIO_BK51"
$PN"BK51"3;
"VDDIO_BJ72"
$PN"BJ72"3;
"VDDIO_BJ65"
$PN"BJ65"3;
"VDDIO_BJ58"
$PN"BJ58"3;
"VDDIO_BJ54"
$PN"BJ54"3;
"VDDIO_BJ52"
$PN"BJ52"3;
"VDDIO_BJ50"
$PN"BJ50"3;
"VDDIO_BH53"
$PN"BH53"3;
"VDDIO_BH51"
$PN"BH51"3;
"VDDIO_BG54"
$PN"BG54"3;
"VDDIO_BG52"
$PN"BG52"3;
"VDDIO_BG50"
$PN"BG50"3;
"VDDIO_BF71"
$PN"BF71"3;
"VDDIO_BF64"
$PN"BF64"3;
"VDDIO_BF57"
$PN"BF57"3;
"VDDIO_BF53"
$PN"BF53"3;
"VDDIO_BF51"
$PN"BF51"3;
"VDDIO_BD54"
$PN"BD54"3;
"VDDIO_BD52"
$PN"BD52"3;
"VDDIO_BD50"
$PN"BD50"3;
"VDDIO_BA72"
$PN"BA72"3;
"VDDIO_BA65"
$PN"BA65"3;
"VDDIO_BA58"
$PN"BA58"3;
"VDDIO_AV71"
$PN"AV71"3;
"VDDIO_AV64"
$PN"AV64"3;
"VDDIO_AV57"
$PN"AV57"3;
"VDDIO_AR72"
$PN"AR72"3;
"VDDIO_AR65"
$PN"AR65"3;
"VDDIO_AR58"
$PN"AR58"3;
"VDDIO_AM71"
$PN"AM71"3;
"VDDIO_AM64"
$PN"AM64"3;
"VDDIO_AM57"
$PN"AM57"3;
"VDDIO_AM54"
$PN"AM54"3;
"VDDIO_AJ72"
$PN"AJ72"3;
"VDDIO_AJ65"
$PN"AJ65"3;
"VDDIO_AJ58"
$PN"AJ58"3;
"VDDIO_AH54"
$PN"AH54"3;
"VDDIO_AF71"
$PN"AF71"3;
"VDDIO_AF64"
$PN"AF64"3;
"VDDIO_AF57"
$PN"AF57"3;
"VDDIO_AD54"
$PN"AD54"3;
"VDDIO_AC72"
$PN"AC72"3;
"VDDIO_AC65"
$PN"AC65"3;
"VDDIO_AC58"
$PN"AC58"3;
"VDDIO_AA54"
$PN"AA54"3;
"VDDIO_Y71"
$PN"Y71"3;
"VDDIO_Y64"
$PN"Y64"3;
"VDDIO_Y57"
$PN"Y57"3;
"VDDIO_V54"
$PN"V54"3;
"VDDIO_U72"
$PN"U72"3;
"VDDIO_U65"
$PN"U65"3;
"VDDIO_U58"
$PN"U58"3;
"VDDIO_P71"
$PN"P71"3;
"VDDIO_P64"
$PN"P64"3;
"VDDIO_P57"
$PN"P57"3;
"VDDIO_P54"
$PN"P54"3;
"VDDIO_L72"
$PN"L72"3;
"VDDIO_L65"
$PN"L65"3;
"VDDIO_L58"
$PN"L58"3;
"VDDIO_K54"
$PN"K54"3;
"VDDIO_H71"
$PN"H71"3;
"VDDIO_H64"
$PN"H64"3;
"VDDIO_H57"
$PN"H57"3;
%"GENOA_SP5"
"23","(-875,4325)","0","pure_quanta","I46";
;
LOCATION"U26"
$SEC"23"
CDS_SEC"23"
PART_TYPE"SMLF"
PART_NUMBER"DGA^6000030"
MATERIAL"IO"
VALUE"SOCKET6096_13568-001"
CDS_LIB"pure_quanta"
CDS_LMAN_SYM_OUTLINE"-550,2000,550,-2000"
NEEDS_NO_SIZE"TRUE";
"TEST6_X3D6"
$PN"B36"0;
"TEST4_CCD15"
$PN"C23"0;
"TEST4_CCD12"
$PN"C58"0;
"TEST5_CCD12"
$PN"C59"0;
"TEST5_CCD15"
$PN"D23"0;
"TEST4_CCD14"
$PN"DF41"0;
"TEST5_CCD14"
$PN"DG42"0;
"TEST4_CCD13"
$PN"DH13"0;
"TEST5_CCD13"
$PN"DH14"0;
"TEST6_X3D7"
$PN"DJ57"0;
"RSVD_A60"
$PN"A60"0;
"RSVD_BD7"
$PN"BD7"0;
"RSVD_D36"
$PN"D36"0;
"RSVD_BD58"
$PN"BD58"0;
"RSVD_BD55"
$PN"BD55"0;
"RSVD_A54"
$PN"A54"0;
"RSVD_A51"
$PN"A51"0;
"RSVD_A50"
$PN"A50"0;
"RSVD_A48"
$PN"A48"0;
"RSVD_C53"
$PN"C53"0;
"RSVD_A45"
$PN"A45"0;
"RSVD_C35"
$PN"C35"0;
"RSVD_D65"
$PN"D65"0;
"RSVD_A42"
$PN"A42"0;
"RSVD_C34"
$PN"C34"0;
"RSVD_D62"
$PN"D62"0;
"RSVD_BD21"
$PN"BD21"0;
"RSVD_A41"
$PN"A41"0;
"RSVD_C31"
$PN"C31"0;
"RSVD_D58"
$PN"D58"0;
"RSVD_BD18"
$PN"BD18"0;
"RSVD_DJ4"
$PN"DJ4"0;
"RSVD_A35"
$PN"A35"0;
"RSVD_B40"
$PN"B40"0;
"RSVD_BD14"
$PN"BD14"0;
"RSVD_DH21"
$PN"DH21"0;
"RSVD_A31"
$PN"A31"0;
"RSVD_D34"
$PN"D34"0;
"RSVD_BD11"
$PN"BD11"0;
"RSVD_DH17"
$PN"DH17"0;
"RSVD_A59"
$PN"A59"0;
"RSVD_D22"
$PN"D22"0;
"RSVD_DG17"
$PN"DG17"0;
"RSVD_A57"
$PN"A57"0;
"RSVD_D11"
$PN"D11"0;
"RSVD_BD4"
$PN"BD4"0;
"RSVD_BD72"
$PN"BD72"0;
"RSVD_A56"
$PN"A56"0;
"RSVD_D8"
$PN"D8"0;
"RSVD_E36"
$PN"E36"0;
"RSVD_BD69"
$PN"BD69"0;
"RSVD_A55"
$PN"A55"0;
"RSVD_D4"
$PN"D4"0;
"RSVD_E33"
$PN"E33"0;
"RSVD_BD65"
$PN"BD65"0;
"RSVD_C54"
$PN"C54"0;
"RSVD_D72"
$PN"D72"0;
"RSVD_BD62"
$PN"BD62"0;
%"VCC_CORE"
"1","(-3825,6250)","0","pure_quanta_power","I47";
;
HDL_POWER"PVDDCR_SOC_P1"
CDS_LIB"pure_quanta_power";
"A"12;
%"VCC_CORE"
"1","(-5125,6250)","0","pure_quanta_power","I48";
;
HDL_POWER"PVDDCR_SOC_P1"
CDS_LIB"pure_quanta_power";
"A"8;
%"GENOA_SP5"
"26","(-4475,4675)","0","pure_quanta","I49";
;
LOCATION"U26"
$SEC"26"
CDS_SEC"26"
PART_TYPE"SMLF"
MATERIAL"IO"
PART_NUMBER"DGA^6000030"
VALUE"SOCKET6096_13568-001"
CDS_LIB"pure_quanta"
CDS_LMAN_SYM_OUTLINE"-450,1650,450,-1650"
NEEDS_NO_SIZE"TRUE";
"VDDCR_SOC_BG22"
$PN"BG22"12;
"VDDCR_SOC_BG24"
$PN"BG24"12;
"VDDCR_SOC_BG26"
$PN"BG26"12;
"VDDCR_SOC_BG28"
$PN"BG28"12;
"VDDCR_SOC_BG48"
$PN"BG48"12;
"VDDCR_SOC_BH23"
$PN"BH23"12;
"VDDCR_SOC_BH25"
$PN"BH25"12;
"VDDCR_SOC_BH48"
$PN"BH48"12;
"VDDCR_SOC_BJ4"
$PN"BJ4"12;
"VDDCR_SOC_BJ11"
$PN"BJ11"12;
"VDDCR_SOC_BJ48"
$PN"BJ48"12;
"VDDCR_SOC_BM5"
$PN"BM5"12;
"VDDCR_SOC_BF48"
$PN"BF48"12;
"VDDCR_SOC_BF27"
$PN"BF27"12;
"VDDCR_SOC_BF25"
$PN"BF25"12;
"VDDCR_SOC_BF23"
$PN"BF23"12;
"VDDCR_SOC_BD48"
$PN"BD48"12;
"VDDCR_SOC_BD28"
$PN"BD28"12;
"VDDCR_SOC_BD26"
$PN"BD26"12;
"VDDCR_SOC_BD24"
$PN"BD24"12;
"VDDCR_SOC_BD22"
$PN"BD22"12;
"VDDCR_SOC_BD19"
$PN"BD19"12;
"VDDCR_SOC_BD12"
$PN"BD12"12;
"VDDCR_SOC_BD5"
$PN"BD5"12;
"VDDCR_SOC_BC48"
$PN"BC48"12;
"VDDCR_SOC_BC27"
$PN"BC27"12;
"VDDCR_SOC_BC25"
$PN"BC25"12;
"VDDCR_SOC_BC23"
$PN"BC23"12;
"VDDCR_SOC_BB49"
$PN"BB49"12;
"VDDCR_SOC_BB28"
$PN"BB28"12;
"VDDCR_SOC_BB26"
$PN"BB26"12;
"VDDCR_SOC_BB24"
$PN"BB24"12;
"VDDCR_SOC_BB22"
$PN"BB22"12;
"VDDCR_SOC_BA48"
$PN"BA48"12;
"VDDCR_SOC_BA27"
$PN"BA27"12;
"VDDCR_SOC_BA25"
$PN"BA25"12;
"VDDCR_SOC_BA23"
$PN"BA23"12;
"VDDCR_SOC_BA18"
$PN"BA18"12;
"VDDCR_SOC_BA11"
$PN"BA11"12;
"VDDCR_SOC_BA4"
$PN"BA4"12;
"VDDCR_SOC_AY49"
$PN"AY49"12;
"VDDCR_SOC_AY28"
$PN"AY28"12;
"VDDCR_SOC_AY26"
$PN"AY26"12;
"VDDCR_SOC_AY24"
$PN"AY24"12;
"VDDCR_SOC_AY22"
$PN"AY22"12;
"VDDCR_SOC_AW48"
$PN"AW48"12;
"VDDCR_SOC_AW27"
$PN"AW27"12;
"VDDCR_SOC_AW25"
$PN"AW25"12;
"VDDCR_SOC_AW23"
$PN"AW23"12;
"VDDCR_SOC_AV47"
$PN"AV47"12;
"VDDCR_SOC_AV45"
$PN"AV45"12;
"VDDCR_SOC_AV43"
$PN"AV43"12;
"VDDCR_SOC_AV41"
$PN"AV41"8;
"VDDCR_SOC_AV39"
$PN"AV39"8;
"VDDCR_SOC_AV36"
$PN"AV36"8;
"VDDCR_SOC_AV34"
$PN"AV34"8;
"VDDCR_SOC_AV32"
$PN"AV32"8;
"VDDCR_SOC_AV30"
$PN"AV30"8;
"VDDCR_SOC_AV28"
$PN"AV28"8;
"VDDCR_SOC_AV26"
$PN"AV26"8;
"VDDCR_SOC_AV24"
$PN"AV24"8;
"VDDCR_SOC_AV22"
$PN"AV22"8;
"VDDCR_SOC_AV19"
$PN"AV19"8;
"VDDCR_SOC_AV12"
$PN"AV12"8;
"VDDCR_SOC_AV5"
$PN"AV5"8;
"VDDCR_SOC_AU40"
$PN"AU40"8;
"VDDCR_SOC_AU35"
$PN"AU35"8;
"VDDCR_SOC_AU31"
$PN"AU31"8;
"VDDCR_SOC_AU27"
$PN"AU27"8;
"VDDCR_SOC_AU23"
$PN"AU23"8;
"VDDCR_SOC_AT22"
$PN"AT22"8;
"VDDCR_SOC_AR18"
$PN"AR18"8;
"VDDCR_SOC_AR11"
$PN"AR11"8;
"VDDCR_SOC_AR4"
$PN"AR4"8;
"VDDCR_SOC_AM22"
$PN"AM22"8;
"VDDCR_SOC_AM19"
$PN"AM19"8;
"VDDCR_SOC_AM12"
$PN"AM12"8;
"VDDCR_SOC_AM5"
$PN"AM5"8;
"VDDCR_SOC_AJ18"
$PN"AJ18"8;
"VDDCR_SOC_AJ11"
$PN"AJ11"8;
"VDDCR_SOC_AJ4"
$PN"AJ4"8;
"VDDCR_SOC_AH22"
$PN"AH22"8;
"VDDCR_SOC_AF19"
$PN"AF19"8;
"VDDCR_SOC_AF12"
$PN"AF12"8;
"VDDCR_SOC_AF5"
$PN"AF5"8;
"VDDCR_SOC_AD22"
$PN"AD22"8;
"VDDCR_SOC_AC18"
$PN"AC18"8;
"VDDCR_SOC_AC11"
$PN"AC11"8;
"VDDCR_SOC_AC4"
$PN"AC4"8;
"VDDCR_SOC_AA22"
$PN"AA22"8;
"VDDCR_SOC_Y19"
$PN"Y19"8;
"VDDCR_SOC_Y12"
$PN"Y12"8;
"VDDCR_SOC_Y5"
$PN"Y5"8;
"VDDCR_SOC_V22"
$PN"V22"8;
"VDDCR_SOC_U18"
$PN"U18"8;
"VDDCR_SOC_U11"
$PN"U11"8;
"VDDCR_SOC_U4"
$PN"U4"8;
"VDDCR_SOC_P22"
$PN"P22"8;
"VDDCR_SOC_P19"
$PN"P19"8;
"VDDCR_SOC_P12"
$PN"P12"8;
"VDDCR_SOC_P5"
$PN"P5"8;
"VDDCR_SOC_L18"
$PN"L18"8;
"VDDCR_SOC_L11"
$PN"L11"8;
"VDDCR_SOC_L4"
$PN"L4"8;
"VDDCR_SOC_K22"
$PN"K22"8;
"VDDCR_SOC_H19"
$PN"H19"8;
"VDDCR_SOC_H12"
$PN"H12"8;
"VDDCR_SOC_H5"
$PN"H5"8;
"VDDCR_SOC_E11"
$PN"E11"8;
"VDDCR_SOC_E4"
$PN"E4"8;
"VDDCR_SOC_C4"
$PN"C4"8;
"VDDCR_SOC_B5"
$PN"B5"8;
%"Q_RES"
"2","(-1125,725)","0","pure_quanta","I51";
;
LOCATION"R374"
$SEC"1"
CDS_SEC"1"
WATTAGE"1/16W"
MATERIAL"CHIP"
TOLERANCE"5%"
VALUE"0"
PACK_TYPE"0402LF"
BOM_COST"MEM"
CDS_LIB"pure_quanta"
PART_NUMBER"CS00002JB38"
ROOM"RST_CPU1_PLD_TO_DIMM";
"A"
$PN"1"1;
"B"
$PN"2"13;
%"Q_RES"
"2","(-1450,725)","0","pure_quanta","I52";
;
LOCATION"R373"
$SEC"1"
CDS_SEC"1"
WATTAGE"1/16W"
MATERIAL"EMPTY"
TOLERANCE"5%"
VALUE"0"
PART_NUMBER"CS00002JB38"
PACK_TYPE"0402LF"
BOM_COST"MEM"
CDS_LIB"pure_quanta"
ROOM"RST_CPU1_PLD_TO_DIMM";
"A"
$PN"1"2;
"B"
$PN"2"13;
END.
